(kicad_pcb
	(version 20241229)
	(generator "pcbnew")
	(generator_version "9.0")
	(general
		(thickness 1.61)
		(legacy_teardrops no)
	)
	(paper "A3")
	(title_block
		(title "SO-DIMM DDR5 Tester")
		(date "2025-11-26")
		(rev "1.3.0")
		(comment 9 "footprint 147 of 627 (J2), pads 1-87 of 266")
	)
	(layers
		(0 "F.Cu" signal)
		(4 "In1.Cu" power)
		(6 "In2.Cu" mixed)
		(8 "In3.Cu" power)
		(10 "In4.Cu" mixed)
		(12 "In5.Cu" power)
		(14 "In6.Cu" mixed)
		(16 "In7.Cu" power)
		(18 "In8.Cu" power)
		(20 "In9.Cu" mixed)
		(22 "In10.Cu" power)
		(2 "B.Cu" signal)
		(9 "F.Adhes" user "F.Adhesive")
		(11 "B.Adhes" user "B.Adhesive")
		(13 "F.Paste" user)
		(15 "B.Paste" user)
		(5 "F.SilkS" user "F.Silkscreen")
		(7 "B.SilkS" user "B.Silkscreen")
		(1 "F.Mask" user)
		(3 "B.Mask" user)
		(17 "Dwgs.User" user "User.Drawings")
		(19 "Cmts.User" user "User.Comments")
		(21 "Eco1.User" user "User.Eco1")
		(23 "Eco2.User" user "User.Eco2")
		(25 "Edge.Cuts" user)
		(27 "Margin" user)
		(31 "F.CrtYd" user "F.Courtyard")
		(29 "B.CrtYd" user "B.Courtyard")
		(35 "F.Fab" user)
		(33 "B.Fab" user)
	)
	(footprint "antmicro-footprints:Bus_DDR5_SODIMM_Amphenol_10161033-002RHLF"
		(layer "F.Cu")
		(at 139.780001 134.8375 180)
		(property "Reference" "J2"
			(at -35.119999 -13.0625 180)
			(layer "F.SilkS")
			(effects
				(font
					(size 0.7 0.7)
					(thickness 0.15)
				)
				(justify left bottom)
			)
		)
		(property "Value" "Bus_DDR5_SODIMM_Amphenol_10161033-002RHLF_CUSTOM_2xDetectPin"
			(at 0 13.5 180)
			(layer "F.Fab")
			(effects
				(font
					(size 0.7 0.7)
					(thickness 0.15)
				)
				(justify left bottom)
			)
		)
		(property "Datasheet" "https://cdn.amphenol-cs.com/media/wysiwyg/files/documentation/datasheet/ssio/ssio_ddr5_sodimm.pdf"
			(at 0 0 180)
			(layer "F.Fab")
			(hide yes)
			(effects
				(font
					(size 1.27 1.27)
					(thickness 0.15)
				)
			)
		)
		(property "Author" "Antmicro"
			(at 279.560002 269.675 0)
			(layer "F.Fab")
			(hide yes)
			(effects
				(font
					(size 1 1)
					(thickness 0.15)
				)
			)
		)
		(property "License" "Apache-2.0"
			(at 279.560002 269.675 0)
			(layer "F.Fab")
			(hide yes)
			(effects
				(font
					(size 1 1)
					(thickness 0.15)
				)
			)
		)
		(property "MPN" "10161033-002RHLF"
			(at 279.560002 269.675 0)
			(layer "F.Fab")
			(hide yes)
			(effects
				(font
					(size 1 1)
					(thickness 0.15)
				)
			)
		)
		(property "Manufacturer" "Amphenol"
			(at 279.560002 269.675 0)
			(layer "F.Fab")
			(hide yes)
			(effects
				(font
					(size 1 1)
					(thickness 0.15)
				)
			)
		)
		(sheetname "/DDR5 SODIMM/")
		(sheetfile "ddr5-sodimm.kicad_sch")
		(attr smd)
		(pad "" np_thru_hole circle
			(at -34.395 -7.065 180)
			(size 1.25 1.25)
			(drill 1.25)
			(layers "*.Cu" "*.Mask")
		)
		(pad "" np_thru_hole circle
			(at 34.405 -7.065 180)
			(size 1.65 1.65)
			(drill 1.65)
			(layers "*.Cu" "*.Mask")
		)
		(pad "1" smd rect
			(at 33.38 -11.365 180)
			(size 0.3 1.5)
			(layers "F.Cu" "F.Mask" "F.Paste")
			(net 201 "+5V")
			(pinfunction "VIN_BULK")
			(pintype "passive")
		)
		(pad "2" smd rect
			(at 33.13 -3.965 180)
			(size 0.3 1.5)
			(layers "F.Cu" "F.Mask" "F.Paste")
			(net 49 "/DDR5 SODIMM/HSA")
			(pinfunction "HSA")
			(pintype "passive")
		)
		(pad "3" smd rect
			(at 32.88 -11.365 180)
			(size 0.3 1.5)
			(layers "F.Cu" "F.Mask" "F.Paste")
			(net 201 "+5V")
			(pinfunction "VIN_BULK")
			(pintype "passive")
		)
		(pad "4" smd rect
			(at 32.63 -3.965 180)
			(size 0.3 1.5)
			(layers "F.Cu" "F.Mask" "F.Paste")
			(net 50 "/DDR5 SODIMM/DDR.SCL")
			(pinfunction "HSCL")
			(pintype "passive")
		)
		(pad "5" smd rect
			(at 32.38 -11.365 180)
			(size 0.3 1.5)
			(layers "F.Cu" "F.Mask" "F.Paste")
			(net 137 "/DDR5 SODIMM/RFU1")
			(pinfunction "RFU")
			(pintype "passive")
		)
		(pad "6" smd rect
			(at 32.13 -3.965 180)
			(size 0.3 1.5)
			(layers "F.Cu" "F.Mask" "F.Paste")
			(net 54 "/DDR5 SODIMM/DDR.SDA")
			(pinfunction "HSDA")
			(pintype "passive")
		)
		(pad "7" smd rect
			(at 31.88 -11.365 180)
			(size 0.3 1.5)
			(layers "F.Cu" "F.Mask" "F.Paste")
			(net 313 "Net-(J2C-PWR_GOOD)")
			(pinfunction "PWR_GOOD")
			(pintype "passive")
		)
		(pad "8" smd rect
			(at 31.63 -3.965 180)
			(size 0.3 1.5)
			(layers "F.Cu" "F.Mask" "F.Paste")
			(net 314 "Net-(J2C-PWR_EN)")
			(pinfunction "PWR_EN")
			(pintype "passive")
		)
		(pad "9" smd rect
			(at 31.38 -11.365 180)
			(size 0.3 1.5)
			(layers "F.Cu" "F.Mask" "F.Paste")
			(net 1 "GND")
			(pinfunction "VSS")
			(pintype "passive")
		)
		(pad "10" smd rect
			(at 31.13 -3.965 180)
			(size 0.3 1.5)
			(layers "F.Cu" "F.Mask" "F.Paste")
			(net 1 "GND")
			(pinfunction "VSS")
			(pintype "passive")
		)
		(pad "11" smd rect
			(at 30.88 -11.365 180)
			(size 0.3 1.5)
			(layers "F.Cu" "F.Mask" "F.Paste")
			(net 55 "/DDR5 SODIMM/A.DQ0")
			(pinfunction "DQ0_A")
			(pintype "passive")
		)
		(pad "12" smd rect
			(at 30.63 -3.965 180)
			(size 0.3 1.5)
			(layers "F.Cu" "F.Mask" "F.Paste")
			(net 57 "/DDR5 SODIMM/A.DQ1")
			(pinfunction "DQ1_A")
			(pintype "passive")
		)
		(pad "13" smd rect
			(at 30.38 -11.365 180)
			(size 0.3 1.5)
			(layers "F.Cu" "F.Mask" "F.Paste")
			(net 1 "GND")
			(pinfunction "VSS")
			(pintype "passive")
		)
		(pad "14" smd rect
			(at 30.13 -3.965 180)
			(size 0.3 1.5)
			(layers "F.Cu" "F.Mask" "F.Paste")
			(net 1 "GND")
			(pinfunction "VSS")
			(pintype "passive")
		)
		(pad "15" smd rect
			(at 29.88 -11.365 180)
			(size 0.3 1.5)
			(layers "F.Cu" "F.Mask" "F.Paste")
			(net 59 "/DDR5 SODIMM/A.DQ2")
			(pinfunction "DQ2_A")
			(pintype "passive")
		)
		(pad "16" smd rect
			(at 29.63 -3.965 180)
			(size 0.3 1.5)
			(layers "F.Cu" "F.Mask" "F.Paste")
			(net 61 "/DDR5 SODIMM/A.DQ3")
			(pinfunction "DQ3_A")
			(pintype "passive")
		)
		(pad "17" smd rect
			(at 29.38 -11.365 180)
			(size 0.3 1.5)
			(layers "F.Cu" "F.Mask" "F.Paste")
			(net 1 "GND")
			(pinfunction "VSS")
			(pintype "passive")
		)
		(pad "18" smd rect
			(at 29.13 -3.965 180)
			(size 0.3 1.5)
			(layers "F.Cu" "F.Mask" "F.Paste")
			(net 1 "GND")
			(pinfunction "VSS")
			(pintype "passive")
		)
		(pad "19" smd rect
			(at 28.88 -11.365 180)
			(size 0.3 1.5)
			(layers "F.Cu" "F.Mask" "F.Paste")
			(net 65 "/DDR5 SODIMM/A.~{DM0}")
			(pinfunction "DM0_A_n")
			(pintype "passive")
		)
		(pad "20" smd rect
			(at 28.63 -3.965 180)
			(size 0.3 1.5)
			(layers "F.Cu" "F.Mask" "F.Paste")
			(net 68 "/DDR5 SODIMM/A.DQS0_N")
			(pinfunction "DQS0_A_C")
			(pintype "passive")
		)
		(pad "21" smd rect
			(at 28.38 -11.365 180)
			(size 0.3 1.5)
			(layers "F.Cu" "F.Mask" "F.Paste")
			(net 1 "GND")
			(pinfunction "VSS")
			(pintype "passive")
		)
		(pad "22" smd rect
			(at 28.13 -3.965 180)
			(size 0.3 1.5)
			(layers "F.Cu" "F.Mask" "F.Paste")
			(net 69 "/DDR5 SODIMM/A.DQS0_P")
			(pinfunction "DQS0_A_t")
			(pintype "passive")
		)
		(pad "23" smd rect
			(at 27.88 -11.365 180)
			(size 0.3 1.5)
			(layers "F.Cu" "F.Mask" "F.Paste")
			(net 70 "/DDR5 SODIMM/A.DQ4")
			(pinfunction "DQ4_A")
			(pintype "passive")
		)
		(pad "24" smd rect
			(at 27.63 -3.965 180)
			(size 0.3 1.5)
			(layers "F.Cu" "F.Mask" "F.Paste")
			(net 1 "GND")
			(pinfunction "VSS")
			(pintype "passive")
		)
		(pad "25" smd rect
			(at 27.38 -11.365 180)
			(size 0.3 1.5)
			(layers "F.Cu" "F.Mask" "F.Paste")
			(net 1 "GND")
			(pinfunction "VSS")
			(pintype "passive")
		)
		(pad "26" smd rect
			(at 27.13 -3.965 180)
			(size 0.3 1.5)
			(layers "F.Cu" "F.Mask" "F.Paste")
			(net 71 "/DDR5 SODIMM/A.DQ5")
			(pinfunction "DQ5_A")
			(pintype "passive")
		)
		(pad "27" smd rect
			(at 26.88 -11.365 180)
			(size 0.3 1.5)
			(layers "F.Cu" "F.Mask" "F.Paste")
			(net 72 "/DDR5 SODIMM/A.DQ6")
			(pinfunction "DQ6_A")
			(pintype "passive")
		)
		(pad "28" smd rect
			(at 26.63 -3.965 180)
			(size 0.3 1.5)
			(layers "F.Cu" "F.Mask" "F.Paste")
			(net 1 "GND")
			(pinfunction "VSS")
			(pintype "passive")
		)
		(pad "29" smd rect
			(at 26.38 -11.365 180)
			(size 0.3 1.5)
			(layers "F.Cu" "F.Mask" "F.Paste")
			(net 1 "GND")
			(pinfunction "VSS")
			(pintype "passive")
		)
		(pad "30" smd rect
			(at 26.13 -3.965 180)
			(size 0.3 1.5)
			(layers "F.Cu" "F.Mask" "F.Paste")
			(net 73 "/DDR5 SODIMM/A.DQ7")
			(pinfunction "DQ7_A")
			(pintype "passive")
		)
		(pad "31" smd rect
			(at 25.88 -11.365 180)
			(size 0.3 1.5)
			(layers "F.Cu" "F.Mask" "F.Paste")
			(net 74 "/DDR5 SODIMM/A.DQ8")
			(pinfunction "DQ8_A")
			(pintype "passive")
		)
		(pad "32" smd rect
			(at 25.63 -3.965 180)
			(size 0.3 1.5)
			(layers "F.Cu" "F.Mask" "F.Paste")
			(net 1 "GND")
			(pinfunction "VSS")
			(pintype "passive")
		)
		(pad "33" smd rect
			(at 25.38 -11.365 180)
			(size 0.3 1.5)
			(layers "F.Cu" "F.Mask" "F.Paste")
			(net 1 "GND")
			(pinfunction "VSS")
			(pintype "passive")
		)
		(pad "34" smd rect
			(at 25.13 -3.965 180)
			(size 0.3 1.5)
			(layers "F.Cu" "F.Mask" "F.Paste")
			(net 77 "/DDR5 SODIMM/A.DQ9")
			(pinfunction "DQ09_A")
			(pintype "passive")
		)
		(pad "35" smd rect
			(at 24.88 -11.365 180)
			(size 0.3 1.5)
			(layers "F.Cu" "F.Mask" "F.Paste")
			(net 79 "/DDR5 SODIMM/A.DQ10")
			(pinfunction "DQ10_A")
			(pintype "passive")
		)
		(pad "36" smd rect
			(at 24.63 -3.965 180)
			(size 0.3 1.5)
			(layers "F.Cu" "F.Mask" "F.Paste")
			(net 1 "GND")
			(pinfunction "VSS")
			(pintype "passive")
		)
		(pad "37" smd rect
			(at 24.38 -11.365 180)
			(size 0.3 1.5)
			(layers "F.Cu" "F.Mask" "F.Paste")
			(net 1 "GND")
			(pinfunction "VSS")
			(pintype "passive")
		)
		(pad "38" smd rect
			(at 24.13 -3.965 180)
			(size 0.3 1.5)
			(layers "F.Cu" "F.Mask" "F.Paste")
			(net 80 "/DDR5 SODIMM/A.DQ11")
			(pinfunction "DQ11_A")
			(pintype "passive")
		)
		(pad "39" smd rect
			(at 23.88 -11.365 180)
			(size 0.3 1.5)
			(layers "F.Cu" "F.Mask" "F.Paste")
			(net 81 "/DDR5 SODIMM/A.DQS1_N")
			(pinfunction "DQS1_A_C")
			(pintype "passive")
		)
		(pad "40" smd rect
			(at 23.63 -3.965 180)
			(size 0.3 1.5)
			(layers "F.Cu" "F.Mask" "F.Paste")
			(net 1 "GND")
			(pinfunction "VSS")
			(pintype "passive")
		)
		(pad "41" smd rect
			(at 23.38 -11.365 180)
			(size 0.3 1.5)
			(layers "F.Cu" "F.Mask" "F.Paste")
			(net 82 "/DDR5 SODIMM/A.DQS1_P")
			(pinfunction "DQS1_A_t")
			(pintype "passive")
		)
		(pad "42" smd rect
			(at 23.13 -3.965 180)
			(size 0.3 1.5)
			(layers "F.Cu" "F.Mask" "F.Paste")
			(net 83 "/DDR5 SODIMM/A.~{DM1}")
			(pinfunction "DM1_A_n")
			(pintype "passive")
		)
		(pad "43" smd rect
			(at 22.88 -11.365 180)
			(size 0.3 1.5)
			(layers "F.Cu" "F.Mask" "F.Paste")
			(net 1 "GND")
			(pinfunction "VSS")
			(pintype "passive")
		)
		(pad "44" smd rect
			(at 22.63 -3.965 180)
			(size 0.3 1.5)
			(layers "F.Cu" "F.Mask" "F.Paste")
			(net 1 "GND")
			(pinfunction "VSS")
			(pintype "passive")
		)
		(pad "45" smd rect
			(at 22.38 -11.365 180)
			(size 0.3 1.5)
			(layers "F.Cu" "F.Mask" "F.Paste")
			(net 84 "/DDR5 SODIMM/A.DQ12")
			(pinfunction "DQ12_A")
			(pintype "passive")
		)
		(pad "46" smd rect
			(at 22.13 -3.965 180)
			(size 0.3 1.5)
			(layers "F.Cu" "F.Mask" "F.Paste")
			(net 85 "/DDR5 SODIMM/A.DQ13")
			(pinfunction "DQ13_A")
			(pintype "passive")
		)
		(pad "47" smd rect
			(at 21.88 -11.365 180)
			(size 0.3 1.5)
			(layers "F.Cu" "F.Mask" "F.Paste")
			(net 1 "GND")
			(pinfunction "VSS")
			(pintype "passive")
		)
		(pad "48" smd rect
			(at 21.63 -3.965 180)
			(size 0.3 1.5)
			(layers "F.Cu" "F.Mask" "F.Paste")
			(net 1 "GND")
			(pinfunction "VSS")
			(pintype "passive")
		)
		(pad "49" smd rect
			(at 21.38 -11.365 180)
			(size 0.3 1.5)
			(layers "F.Cu" "F.Mask" "F.Paste")
			(net 87 "/DDR5 SODIMM/A.DQ14")
			(pinfunction "DQ14_A")
			(pintype "passive")
		)
		(pad "50" smd rect
			(at 21.13 -3.965 180)
			(size 0.3 1.5)
			(layers "F.Cu" "F.Mask" "F.Paste")
			(net 88 "/DDR5 SODIMM/A.DQ15")
			(pinfunction "DQ15_A")
			(pintype "passive")
		)
		(pad "51" smd rect
			(at 20.88 -11.365 180)
			(size 0.3 1.5)
			(layers "F.Cu" "F.Mask" "F.Paste")
			(net 1 "GND")
			(pinfunction "VSS")
			(pintype "passive")
		)
		(pad "52" smd rect
			(at 20.63 -3.965 180)
			(size 0.3 1.5)
			(layers "F.Cu" "F.Mask" "F.Paste")
			(net 1 "GND")
			(pinfunction "VSS")
			(pintype "passive")
		)
		(pad "53" smd rect
			(at 20.38 -11.365 180)
			(size 0.3 1.5)
			(layers "F.Cu" "F.Mask" "F.Paste")
			(net 89 "/DDR5 SODIMM/A.DQ16")
			(pinfunction "DQ16_A")
			(pintype "passive")
		)
		(pad "54" smd rect
			(at 20.13 -3.965 180)
			(size 0.3 1.5)
			(layers "F.Cu" "F.Mask" "F.Paste")
			(net 91 "/DDR5 SODIMM/A.DQ17")
			(pinfunction "DQ17_A")
			(pintype "passive")
		)
		(pad "55" smd rect
			(at 19.88 -11.365 180)
			(size 0.3 1.5)
			(layers "F.Cu" "F.Mask" "F.Paste")
			(net 1 "GND")
			(pinfunction "VSS")
			(pintype "passive")
		)
		(pad "56" smd rect
			(at 19.63 -3.965 180)
			(size 0.3 1.5)
			(layers "F.Cu" "F.Mask" "F.Paste")
			(net 1 "GND")
			(pinfunction "VSS")
			(pintype "passive")
		)
		(pad "57" smd rect
			(at 19.38 -11.365 180)
			(size 0.3 1.5)
			(layers "F.Cu" "F.Mask" "F.Paste")
			(net 92 "/DDR5 SODIMM/A.DQ18")
			(pinfunction "DQ18_A")
			(pintype "passive")
		)
		(pad "58" smd rect
			(at 19.13 -3.965 180)
			(size 0.3 1.5)
			(layers "F.Cu" "F.Mask" "F.Paste")
			(net 93 "/DDR5 SODIMM/A.DQ19")
			(pinfunction "DQ19_A")
			(pintype "passive")
		)
		(pad "59" smd rect
			(at 18.88 -11.365 180)
			(size 0.3 1.5)
			(layers "F.Cu" "F.Mask" "F.Paste")
			(net 1 "GND")
			(pinfunction "VSS")
			(pintype "passive")
		)
		(pad "60" smd rect
			(at 18.63 -3.965 180)
			(size 0.3 1.5)
			(layers "F.Cu" "F.Mask" "F.Paste")
			(net 1 "GND")
			(pinfunction "VSS")
			(pintype "passive")
		)
		(pad "61" smd rect
			(at 18.38 -11.365 180)
			(size 0.3 1.5)
			(layers "F.Cu" "F.Mask" "F.Paste")
			(net 94 "/DDR5 SODIMM/A.~{DM2}")
			(pinfunction "DM2_A_n")
			(pintype "passive")
		)
		(pad "62" smd rect
			(at 18.13 -3.965 180)
			(size 0.3 1.5)
			(layers "F.Cu" "F.Mask" "F.Paste")
			(net 95 "/DDR5 SODIMM/A.DQS2_N")
			(pinfunction "DQS2_A_C")
			(pintype "passive")
		)
		(pad "63" smd rect
			(at 17.88 -11.365 180)
			(size 0.3 1.5)
			(layers "F.Cu" "F.Mask" "F.Paste")
			(net 1 "GND")
			(pinfunction "VSS")
			(pintype "passive")
		)
		(pad "64" smd rect
			(at 17.63 -3.965 180)
			(size 0.3 1.5)
			(layers "F.Cu" "F.Mask" "F.Paste")
			(net 96 "/DDR5 SODIMM/A.DQS2_P")
			(pinfunction "DQS2_A_t")
			(pintype "passive")
		)
		(pad "65" smd rect
			(at 17.38 -11.365 180)
			(size 0.3 1.5)
			(layers "F.Cu" "F.Mask" "F.Paste")
			(net 97 "/DDR5 SODIMM/A.DQ20")
			(pinfunction "DQ20_A")
			(pintype "passive")
		)
		(pad "66" smd rect
			(at 17.13 -3.965 180)
			(size 0.3 1.5)
			(layers "F.Cu" "F.Mask" "F.Paste")
			(net 1 "GND")
			(pinfunction "VSS")
			(pintype "passive")
		)
		(pad "67" smd rect
			(at 16.88 -11.365 180)
			(size 0.3 1.5)
			(layers "F.Cu" "F.Mask" "F.Paste")
			(net 1 "GND")
			(pinfunction "VSS")
			(pintype "passive")
		)
		(pad "68" smd rect
			(at 16.63 -3.965 180)
			(size 0.3 1.5)
			(layers "F.Cu" "F.Mask" "F.Paste")
			(net 98 "/DDR5 SODIMM/A.DQ21")
			(pinfunction "DQ21_A")
			(pintype "passive")
		)
		(pad "69" smd rect
			(at 16.38 -11.365 180)
			(size 0.3 1.5)
			(layers "F.Cu" "F.Mask" "F.Paste")
			(net 99 "/DDR5 SODIMM/A.DQ22")
			(pinfunction "DQ22_A")
			(pintype "passive")
		)
		(pad "70" smd rect
			(at 16.13 -3.965 180)
			(size 0.3 1.5)
			(layers "F.Cu" "F.Mask" "F.Paste")
			(net 1 "GND")
			(pinfunction "VSS")
			(pintype "passive")
		)
		(pad "71" smd rect
			(at 15.88 -11.365 180)
			(size 0.3 1.5)
			(layers "F.Cu" "F.Mask" "F.Paste")
			(net 1 "GND")
			(pinfunction "VSS")
			(pintype "passive")
		)
		(pad "72" smd rect
			(at 15.63 -3.965 180)
			(size 0.3 1.5)
			(layers "F.Cu" "F.Mask" "F.Paste")
			(net 100 "/DDR5 SODIMM/A.DQ23")
			(pinfunction "DQ23_A")
			(pintype "passive")
		)
		(pad "73" smd rect
			(at 15.38 -11.365 180)
			(size 0.3 1.5)
			(layers "F.Cu" "F.Mask" "F.Paste")
			(net 102 "/DDR5 SODIMM/A.DQ24")
			(pinfunction "DQ24_A")
			(pintype "passive")
		)
		(pad "74" smd rect
			(at 15.13 -3.965 180)
			(size 0.3 1.5)
			(layers "F.Cu" "F.Mask" "F.Paste")
			(net 1 "GND")
			(pinfunction "VSS")
			(pintype "passive")
		)
		(pad "75" smd rect
			(at 14.88 -11.365 180)
			(size 0.3 1.5)
			(layers "F.Cu" "F.Mask" "F.Paste")
			(net 1 "GND")
			(pinfunction "VSS")
			(pintype "passive")
		)
		(pad "76" smd rect
			(at 14.63 -3.965 180)
			(size 0.3 1.5)
			(layers "F.Cu" "F.Mask" "F.Paste")
			(net 103 "/DDR5 SODIMM/A.DQ25")
			(pinfunction "DQ25_A")
			(pintype "passive")
		)
		(pad "77" smd rect
			(at 14.38 -11.365 180)
			(size 0.3 1.5)
			(layers "F.Cu" "F.Mask" "F.Paste")
			(net 104 "/DDR5 SODIMM/A.DQ26")
			(pinfunction "DQ26_A")
			(pintype "passive")
		)
		(pad "78" smd rect
			(at 14.13 -3.965 180)
			(size 0.3 1.5)
			(layers "F.Cu" "F.Mask" "F.Paste")
			(net 1 "GND")
			(pinfunction "VSS")
			(pintype "passive")
		)
		(pad "79" smd rect
			(at 13.88 -11.365 180)
			(size 0.3 1.5)
			(layers "F.Cu" "F.Mask" "F.Paste")
			(net 1 "GND")
			(pinfunction "VSS")
			(pintype "passive")
		)
		(pad "80" smd rect
			(at 13.63 -3.965 180)
			(size 0.3 1.5)
			(layers "F.Cu" "F.Mask" "F.Paste")
			(net 105 "/DDR5 SODIMM/A.DQ27")
			(pinfunction "DQ27_A")
			(pintype "passive")
		)
		(pad "81" smd rect
			(at 13.38 -11.365 180)
			(size 0.3 1.5)
			(layers "F.Cu" "F.Mask" "F.Paste")
			(net 107 "/DDR5 SODIMM/A.DQS3_N")
			(pinfunction "DQS3_A_C")
			(pintype "passive")
		)
		(pad "82" smd rect
			(at 13.13 -3.965 180)
			(size 0.3 1.5)
			(layers "F.Cu" "F.Mask" "F.Paste")
			(net 1 "GND")
			(pinfunction "VSS")
			(pintype "passive")
		)
		(pad "83" smd rect
			(at 12.88 -11.365 180)
			(size 0.3 1.5)
			(layers "F.Cu" "F.Mask" "F.Paste")
			(net 108 "/DDR5 SODIMM/A.DQS3_P")
			(pinfunction "DQS3_A_t")
			(pintype "passive")
		)
		(pad "84" smd rect
			(at 12.63 -3.965 180)
			(size 0.3 1.5)
			(layers "F.Cu" "F.Mask" "F.Paste")
			(net 109 "/DDR5 SODIMM/A.~{DM3}")
			(pinfunction "DM3_A_n")
			(pintype "passive")
		)
		(pad "85" smd rect
			(at 12.38 -11.365 180)
			(size 0.3 1.5)
			(layers "F.Cu" "F.Mask" "F.Paste")
			(net 1 "GND")
			(pinfunction "VSS")
			(pintype "passive")
		)
	)
)
